# S9S_MB_2U (Grand Teton) — schematic netlist excerpt (pin names and nets, part order shuffled) for the footprints in the layout excerpt that follows; sources: Cadence DE-HDL packaged netlist, KiCad conversion of 03242023_DA0F0TMBIJ0_F0T_Motherboard_J_brd_V01_OCP.brd

PR1790  Q_RES  3.3 1% CHIP  pkg 0402LF  page 287 : A = SW_PVCCIN_CPU1_BOOT6 ; B = SW_PVCCIN_CPU1_BOOT6_R
PR3786  Q_RES  160K 1% EMPTY  pkg 0402LF  page 156 : A = P12V_AUX ; B = P12V_OCP_UV_1

(kicad_pcb
	(version 20260206)
	(generator "pcbnew")
	(generator_version "10.0")
	(general
		(thickness 1.6)
		(legacy_teardrops no)
	)
	(paper "A4")
	(title_block
		(title "03242023_DA0F0TMBIJ0_F0T_Motherboard_J_brd_V01_OCP.brd")
		(comment 1 "Grand Teton / footprints 3078-3079 of 6105")
	)
	(layers
		(0 "F.Cu" signal "TOP")
		(4 "In1.Cu" signal "GND")
		(6 "In2.Cu" signal "IN1")
		(8 "In3.Cu" signal "GND1")
		(10 "In4.Cu" signal "IN2")
		(12 "In5.Cu" signal "GND2")
		(14 "In6.Cu" signal "IN3")
		(16 "In7.Cu" signal "GND3")
		(18 "In8.Cu" signal "VCC")
		(20 "In9.Cu" signal "VCC1")
		(22 "In10.Cu" signal "GND4")
		(24 "In11.Cu" signal "IN4")
		(26 "In12.Cu" signal "GND5")
		(28 "In13.Cu" signal "IN5")
		(30 "In14.Cu" signal "GND6")
		(32 "In15.Cu" signal "IN6")
		(34 "In16.Cu" signal "GND7")
		(2 "B.Cu" signal "BOTTOM")
		(9 "F.Adhes" user "F.Adhesive")
		(11 "B.Adhes" user "B.Adhesive")
		(13 "F.Paste" user "Package Geometry/Pastemask Top")
		(15 "B.Paste" user "Package Geometry/Pastemask Bottom")
		(5 "F.SilkS" user "Ref Des/Silkscreen Top")
		(7 "B.SilkS" user "Ref Des/Silkscreen Bottom")
		(1 "F.Mask" user "Board Geometry/Soldermask Top")
		(3 "B.Mask" user "Board Geometry/Soldermask Bottom")
		(17 "Dwgs.User" user "User.Drawings")
		(19 "Cmts.User" user "User.Comments")
		(21 "Eco1.User" user "User.Eco1")
		(23 "Eco2.User" user "User.Eco2")
		(25 "Edge.Cuts" user "Board Geometry/Outline")
		(27 "Margin" user)
		(31 "F.CrtYd" user "Package Geometry/Place Bound Top")
		(29 "B.CrtYd" user "Package Geometry/Place Bound Bottom")
		(35 "F.Fab" user "Ref Des/Assembly Top")
		(33 "B.Fab" user "Ref Des/Assembly Bottom")
	)
	(footprint ""
		(layer "F.Cu")
		(at 447.557652 -18.449798)
		(property "Reference" "PR3786"
			(at 0 0 0)
			(layer "F.SilkS")
			(hide yes)
			(effects
				(font
					(size 1.27 1.27)
				)
			)
		)
		(property "Value" ""
			(at 0 0 0)
			(layer "F.Fab")
			(effects
				(font
					(size 1.27 1.27)
				)
			)
		)
		(duplicate_pad_numbers_are_jumpers no)
		(fp_line
			(start -0.7874 -0.4064)
			(end 0.7874 -0.4064)
			(stroke
				(width 0.1524)
				(type default)
			)
			(layer "F.SilkS")
		)
		(fp_line
			(start -0.7874 0.4064)
			(end -0.7874 -0.4064)
			(stroke
				(width 0.1524)
				(type default)
			)
			(layer "F.SilkS")
		)
		(fp_line
			(start 0.7874 -0.4064)
			(end 0.7874 0.4064)
			(stroke
				(width 0.1524)
				(type default)
			)
			(layer "F.SilkS")
		)
		(fp_line
			(start 0.7874 0.4064)
			(end -0.7874 0.4064)
			(stroke
				(width 0.1524)
				(type default)
			)
			(layer "F.SilkS")
		)
		(fp_line
			(start -0.67945 -0.305054)
			(end -0.12065 -0.305054)
			(stroke
				(width 0.1)
				(type default)
			)
			(layer "F.Fab")
		)
		(fp_line
			(start -0.67945 0.3048)
			(end -0.67945 -0.305054)
			(stroke
				(width 0.1)
				(type default)
			)
			(layer "F.Fab")
		)
		(fp_line
			(start -0.12065 -0.305054)
			(end -0.12065 -0.2794)
			(stroke
				(width 0.1)
				(type default)
			)
			(layer "F.Fab")
		)
		(fp_line
			(start -0.12065 -0.2794)
			(end 0.12065 -0.2794)
			(stroke
				(width 0.1)
				(type default)
			)
			(layer "F.Fab")
		)
		(fp_line
			(start -0.12065 0.2794)
			(end -0.12065 0.3048)
			(stroke
				(width 0.1)
				(type default)
			)
			(layer "F.Fab")
		)
		(fp_line
			(start -0.12065 0.3048)
			(end -0.67945 0.3048)
			(stroke
				(width 0.1)
				(type default)
			)
			(layer "F.Fab")
		)
		(fp_line
			(start 0.120396 0.2794)
			(end -0.12065 0.2794)
			(stroke
				(width 0.1)
				(type default)
			)
			(layer "F.Fab")
		)
		(fp_line
			(start 0.120396 0.3048)
			(end 0.120396 0.2794)
			(stroke
				(width 0.1)
				(type default)
			)
			(layer "F.Fab")
		)
		(fp_line
			(start 0.12065 -0.3048)
			(end 0.67945 -0.3048)
			(stroke
				(width 0.1)
				(type default)
			)
			(layer "F.Fab")
		)
		(fp_line
			(start 0.12065 -0.2794)
			(end 0.12065 -0.3048)
			(stroke
				(width 0.1)
				(type default)
			)
			(layer "F.Fab")
		)
		(fp_line
			(start 0.67945 -0.3048)
			(end 0.67945 0.3048)
			(stroke
				(width 0.1)
				(type default)
			)
			(layer "F.Fab")
		)
		(fp_line
			(start 0.67945 0.3048)
			(end 0.120396 0.3048)
			(stroke
				(width 0.1)
				(type default)
			)
			(layer "F.Fab")
		)
		(pad "1" smd circle
			(at -0.40005 0)
			(size 0 0)
			(layers "F.Cu" "F.Mask" "F.Paste")
			(net "P12V_AUX")
		)
		(pad "2" smd circle
			(at 0.40005 0)
			(size 0 0)
			(layers "F.Cu" "F.Mask" "F.Paste")
			(net "P12V_OCP_UV_1")
		)
	)
	(footprint ""
		(layer "F.Cu")
		(at 89.596468 -341.729822 90)
		(property "Reference" "PR1790"
			(at 0 0 90)
			(layer "F.SilkS")
			(hide yes)
			(effects
				(font
					(size 1.27 1.27)
				)
			)
		)
		(property "Value" ""
			(at 0 0 90)
			(layer "F.Fab")
			(effects
				(font
					(size 1.27 1.27)
				)
			)
		)
		(duplicate_pad_numbers_are_jumpers no)
		(fp_line
			(start 0.7874 -0.4064)
			(end 0.7874 0.4064)
			(stroke
				(width 0.1524)
				(type default)
			)
			(layer "F.SilkS")
		)
		(fp_line
			(start -0.7874 -0.4064)
			(end 0.7874 -0.4064)
			(stroke
				(width 0.1524)
				(type default)
			)
			(layer "F.SilkS")
		)
		(fp_line
			(start 0.7874 0.4064)
			(end -0.7874 0.4064)
			(stroke
				(width 0.1524)
				(type default)
			)
			(layer "F.SilkS")
		)
		(fp_line
			(start -0.7874 0.4064)
			(end -0.7874 -0.4064)
			(stroke
				(width 0.1524)
				(type default)
			)
			(layer "F.SilkS")
		)
		(fp_line
			(start -0.12065 -0.305054)
			(end -0.12065 -0.2794)
			(stroke
				(width 0.1)
				(type default)
			)
			(layer "F.Fab")
		)
		(fp_line
			(start -0.67945 -0.305054)
			(end -0.12065 -0.305054)
			(stroke
				(width 0.1)
				(type default)
			)
			(layer "F.Fab")
		)
		(fp_line
			(start 0.67945 -0.3048)
			(end 0.67945 0.3048)
			(stroke
				(width 0.1)
				(type default)
			)
			(layer "F.Fab")
		)
		(fp_line
			(start 0.12065 -0.3048)
			(end 0.67945 -0.3048)
			(stroke
				(width 0.1)
				(type default)
			)
			(layer "F.Fab")
		)
		(fp_line
			(start 0.12065 -0.2794)
			(end 0.12065 -0.3048)
			(stroke
				(width 0.1)
				(type default)
			)
			(layer "F.Fab")
		)
		(fp_line
			(start -0.12065 -0.2794)
			(end 0.12065 -0.2794)
			(stroke
				(width 0.1)
				(type default)
			)
			(layer "F.Fab")
		)
		(fp_line
			(start 0.120396 0.2794)
			(end -0.12065 0.2794)
			(stroke
				(width 0.1)
				(type default)
			)
			(layer "F.Fab")
		)
		(fp_line
			(start -0.12065 0.2794)
			(end -0.12065 0.3048)
			(stroke
				(width 0.1)
				(type default)
			)
			(layer "F.Fab")
		)
		(fp_line
			(start 0.67945 0.3048)
			(end 0.120396 0.3048)
			(stroke
				(width 0.1)
				(type default)
			)
			(layer "F.Fab")
		)
		(fp_line
			(start 0.120396 0.3048)
			(end 0.120396 0.2794)
			(stroke
				(width 0.1)
				(type default)
			)
			(layer "F.Fab")
		)
		(fp_line
			(start -0.12065 0.3048)
			(end -0.67945 0.3048)
			(stroke
				(width 0.1)
				(type default)
			)
			(layer "F.Fab")
		)
		(fp_line
			(start -0.67945 0.3048)
			(end -0.67945 -0.305054)
			(stroke
				(width 0.1)
				(type default)
			)
			(layer "F.Fab")
		)
		(pad "1" smd circle
			(at -0.40005 0 90)
			(size 0 0)
			(layers "F.Cu" "F.Mask" "F.Paste")
			(net "SW_PVCCIN_CPU1_BOOT6")
		)
		(pad "2" smd circle
			(at 0.40005 0 90)
			(size 0 0)
			(layers "F.Cu" "F.Mask" "F.Paste")
			(net "SW_PVCCIN_CPU1_BOOT6_R")
		)
	)
)
